# Stackup_F0T_Expander_BD_18L_3p09mm_EM-890K_VL411_Rev1_20221220.xls — Stackup (pcb-stackup)
| STACKUP |  |  |  | Target Z (ohms) - MicroStrip |  |  |  |  | 50 | Breakout | 85 |  | 95 |  | 100 |  |  |  | Breakout |  |
|  |  |  |  | Target Z (ohms) - StripLine |  |  |  |  | 50 |  | 85 |  | 95 |  | 100 |  | 85(neck mode) target |  |  |  |
|  |  |  |  | Z tolerance |  |  |  |  | 0.1 |  | +/-7.5% (for inner) ,+/-10% (for outer) |  | 0.1 |  | 0.1 |  | 0.1 |  |  |  |
|  |  |  |  | Z Type |  |  |  |  | Single | Single | Differential |  | Differential |  | Differential |  | Differential |  | Differential |  |
| Layer# | Material | Description |  | Copper Weight (oz) | Thickness (mil) | Tolerance (mil) | Glass Fabric | Er | Width | Width | Width | Space | Width | Space | Width | Space | Width | Space | Width | Space |
|  |  |  | Soldermask |  | 0.6 |  |  | 3.8 |  |  |  |  |  |  |  |  |  |  |  |  |
| 1 |  |  | TOP | 0.5+plating | 1.95 |  |  |  | 5.2 | 3.5 | 5.3 | 5.5 | 4.9 | 9.4 | 4.5 | 10 |  |  | 3.5 | 4.5 |
|  | EM-890K |  | PP |  | 2.7 | ±0.709 | 1078x1 | 2.92 |  |  |  |  |  |  |  |  |  |  |  |  |
| 2 |  |  | GND | 1 (VL411) | 1.3 |  |  |  |  |  |  |  |  |  |  |  |  |  |  |  |
|  | EM-890K |  | CORE |  | 4 | ±0.709 | 1078x1 | 2.93 |  |  |  |  |  |  |  |  |  |  |  |  |
| 3 |  |  | VCC | 1 (VL411) | 1.3 |  |  |  |  |  |  |  |  |  |  |  |  |  |  |  |
|  | EM-890K |  | PP |  | 8 | ±1.5 | 3313x2 | 2.97 |  |  |  |  |  |  |  |  |  |  |  |  |
| 4 |  |  | VCC1 | 2 (RTF) | 2.6 |  |  |  |  |  |  |  |  |  |  |  |  |  |  |  |
|  | EM-890K |  | CORE |  | 4 | ±0.709 | 1078x1 | 2.93 |  |  |  |  |  |  |  |  |  |  |  |  |
| 5 |  |  | GND1 | 1 (VL411) | 1.3 |  |  |  |  |  |  |  |  |  |  |  |  |  |  |  |
|  | EM-890K |  | PP |  | 8 | ±1.5 | 3313x2 | 2.97 |  |  |  |  |  |  |  |  |  |  |  |  |
| 6 |  |  | IN1 | 1 (VL411) | 1.3 |  |  |  | 6.1 | 3.5 | 6.5 | 4.6 | 6.3 | 9.5 | 5.5 | 7.5 | 4.5 | 3 | 3.5 | 4 |
|  | EM-890K |  | CORE |  | 4 | ±0.709 | 1078x1 | 2.93 |  |  |  |  |  |  |  |  |  |  |  |  |
| 7 |  |  | GND2 | 1 (VL411) | 1.3 |  |  |  |  |  |  |  |  |  |  |  |  |  |  |  |
|  | EM-890K |  | PP |  | 8 | ±1.5 | 3313x2 | 2.97 |  |  |  |  |  |  |  |  |  |  |  |  |
| 8 |  |  | IN2 | 1 (VL411) | 1.3 |  |  |  | 6.1 | 3.5 | 6.5 | 4.6 | 6.3 | 9.5 | 5.5 | 7.5 | 4.5 | 3 | 3.5 | 4 |
|  | EM-890K |  | CORE |  | 4 | ±0.709 | 1078x1 | 2.93 |  |  |  |  |  |  |  |  |  |  |  |  |
| 9 |  |  | GND3 | 1 (VL411) | 1.3 |  |  |  |  |  |  |  |  |  |  |  |  |  |  |  |
|  | EM-890K |  | PP |  | 7.8 | ±1.5 | 3313x2 | 2.97 |  |  |  |  |  |  |  |  |  |  |  |  |
| 10 |  |  | IN3 | 1 (VL411) | 1.3 |  |  |  | 6.1 | 3.5 | 6.5 | 4.6 | 6.3 | 9.5 | 5.5 | 7.5 | 4.5 | 3 | 3.5 | 4 |
|  | EM-890K |  | CORE |  | 4 | ±0.709 | 1078x1 | 2.93 |  |  |  |  |  |  |  |  |  |  |  |  |
| 11 |  |  | GND4 | 1 (VL411) | 1.3 |  |  |  |  |  |  |  |  |  |  |  |  |  |  |  |
|  | EM-890K |  | PP |  | 8 | ±1.5 | 3313x2 | 2.97 |  |  |  |  |  |  |  |  |  |  |  |  |
| 12 |  |  | IN4 | 1 (VL411) | 1.3 |  |  |  | 6.1 | 3.5 | 6.5 | 4.6 | 6.3 | 9.5 | 5.5 | 7.5 | 4.5 | 3 | 3.5 | 4 |
|  | EM-890K |  | CORE |  | 4 | ±0.709 | 1078x1 | 2.93 |  |  |  |  |  |  |  |  |  |  |  |  |
| 13 |  |  | GND5 | 1 (VL411) | 1.3 |  |  |  |  |  |  |  |  |  |  |  |  |  |  |  |
|  | EM-890K |  | PP |  | 8 | ±1.5 | 3313x2 | 2.97 |  |  |  |  |  |  |  |  |  |  |  |  |
| 14 |  |  | IN5 | 1 (VL411) | 1.3 |  |  |  | 6.1 | 3.5 | 6.5 | 4.6 | 6.3 | 9.5 | 5.5 | 7.5 | 4.5 | 3 | 3.5 | 4 |
|  | EM-890K |  | CORE |  | 4 | ±0.709 | 1078x1 | 2.93 |  |  |  |  |  |  |  |  |  |  |  |  |
| 15 |  |  | GND6 | 2 (RTF) | 2.6 |  |  |  |  |  |  |  |  |  |  |  |  |  |  |  |
|  | EM-890K |  | PP |  | 8 | ±1.5 | 3313x2 | 2.97 |  |  |  |  |  |  |  |  |  |  |  |  |
| 16 |  |  | IN6 | 1 (VL411) | 1.3 |  |  |  | 6.1 | 3.5 | 6.5 | 4.6 | 6.3 | 9.5 | 5.5 | 7.5 | 4.5 | 3 | 3.5 | 4 |
|  | EM-890K |  | CORE |  | 4 | ±0.709 | 1078x1 | 2.93 |  |  |  |  |  |  |  |  |  |  |  |  |
| 17 |  |  | GND7 | 1 (VL411) | 1.3 |  |  |  |  |  |  |  |  |  |  |  |  |  |  |  |
|  | EM-890K |  | PP |  | 2.7 | ±0.709 | 1078x1 | 2.92 |  |  |  |  |  |  |  |  |  |  |  |  |
| 18 |  |  | BOTTOM | 0.5+plating | 1.95 |  |  |  | 5.2 | 3.5 | 5.3 | 5.5 | 4.9 | 9.4 | 4.5 | 10 |  |  | 3.5 | 4.5 |
|  |  |  | Soldermask |  | 0.6 |  |  | 3.8 |  |  |  |  |  |  |  |  |  |  |  |  |
|  |  |  |  | Total | 121.69999999999996 | ±10% |  |  |  |  |  |  |  |  |  |  |  |  |  |  |
